(kicad_pcb
	(version 20260206)
	(generator "pcbnew")
	(generator_version "10.0")
	(general
		(thickness 1.6)
		(legacy_teardrops no)
	)
	(paper "A4")
	(title_block
		(title "04192023_DAF0TMB3IC0_F0TG_MB_C_brd_V02_OCP.brd")
		(comment 1 "Grand Teton / footprints 7222-7228 of 8354")
	)
	(layers
		(0 "F.Cu" signal "TOP")
		(4 "In1.Cu" signal "GND")
		(6 "In2.Cu" signal "IN1")
		(8 "In3.Cu" signal "GND1")
		(10 "In4.Cu" signal "IN2")
		(12 "In5.Cu" signal "GND2")
		(14 "In6.Cu" signal "IN3")
		(16 "In7.Cu" signal "GND3")
		(18 "In8.Cu" signal "VCC")
		(20 "In9.Cu" signal "VCC1")
		(22 "In10.Cu" signal "GND4")
		(24 "In11.Cu" signal "IN4")
		(26 "In12.Cu" signal "GND5")
		(28 "In13.Cu" signal "IN5")
		(30 "In14.Cu" signal "GND6")
		(32 "In15.Cu" signal "IN6")
		(34 "In16.Cu" signal "GND7")
		(2 "B.Cu" signal "BOTTOM")
		(9 "F.Adhes" user "F.Adhesive")
		(11 "B.Adhes" user "B.Adhesive")
		(13 "F.Paste" user "Package Geometry/Pastemask Top")
		(15 "B.Paste" user "Package Geometry/Pastemask Bottom")
		(5 "F.SilkS" user "Ref Des/Silkscreen Top")
		(7 "B.SilkS" user "Ref Des/Silkscreen Bottom")
		(1 "F.Mask" user "Board Geometry/Soldermask Top")
		(3 "B.Mask" user "Board Geometry/Soldermask Bottom")
		(17 "Dwgs.User" user "User.Drawings")
		(19 "Cmts.User" user "User.Comments")
		(21 "Eco1.User" user "User.Eco1")
		(23 "Eco2.User" user "User.Eco2")
		(25 "Edge.Cuts" user "Board Geometry/Outline")
		(27 "Margin" user)
		(31 "F.CrtYd" user "Package Geometry/Place Bound Top")
		(29 "B.CrtYd" user "Package Geometry/Place Bound Bottom")
		(35 "F.Fab" user "Ref Des/Assembly Top")
		(33 "B.Fab" user "Ref Des/Assembly Bottom")
	)
	(footprint ""
		(layer "B.Cu")
		(at 40.9956 -193.996564)
		(property "Reference" "R105"
			(at 0 0 0)
			(layer "B.SilkS")
			(hide yes)
			(effects
				(font
					(size 1.27 1.27)
				)
				(justify mirror)
			)
		)
		(property "Value" ""
			(at 0 0 0)
			(layer "B.Fab")
			(effects
				(font
					(size 1.27 1.27)
				)
				(justify mirror)
			)
		)
		(duplicate_pad_numbers_are_jumpers no)
		(fp_line
			(start -0.7874 -0.4064)
			(end -0.7874 0.4064)
			(stroke
				(width 0.1524)
				(type default)
			)
			(layer "B.SilkS")
		)
		(fp_line
			(start -0.7874 0.4064)
			(end 0.7874 0.4064)
			(stroke
				(width 0.1524)
				(type default)
			)
			(layer "B.SilkS")
		)
		(fp_line
			(start 0.7874 -0.4064)
			(end -0.7874 -0.4064)
			(stroke
				(width 0.1524)
				(type default)
			)
			(layer "B.SilkS")
		)
		(fp_line
			(start 0.7874 0.4064)
			(end 0.7874 -0.4064)
			(stroke
				(width 0.1524)
				(type default)
			)
			(layer "B.SilkS")
		)
		(fp_line
			(start -0.67945 -0.3048)
			(end -0.67945 0.3048)
			(stroke
				(width 0.1)
				(type default)
			)
			(layer "B.Fab")
		)
		(fp_line
			(start -0.67945 0.3048)
			(end -0.120396 0.3048)
			(stroke
				(width 0.1)
				(type default)
			)
			(layer "B.Fab")
		)
		(fp_line
			(start -0.12065 -0.3048)
			(end -0.67945 -0.3048)
			(stroke
				(width 0.1)
				(type default)
			)
			(layer "B.Fab")
		)
		(fp_line
			(start -0.12065 -0.2794)
			(end -0.12065 -0.3048)
			(stroke
				(width 0.1)
				(type default)
			)
			(layer "B.Fab")
		)
		(fp_line
			(start -0.120396 0.2794)
			(end 0.12065 0.2794)
			(stroke
				(width 0.1)
				(type default)
			)
			(layer "B.Fab")
		)
		(fp_line
			(start -0.120396 0.3048)
			(end -0.120396 0.2794)
			(stroke
				(width 0.1)
				(type default)
			)
			(layer "B.Fab")
		)
		(fp_line
			(start 0.12065 -0.305054)
			(end 0.12065 -0.2794)
			(stroke
				(width 0.1)
				(type default)
			)
			(layer "B.Fab")
		)
		(fp_line
			(start 0.12065 -0.2794)
			(end -0.12065 -0.2794)
			(stroke
				(width 0.1)
				(type default)
			)
			(layer "B.Fab")
		)
		(fp_line
			(start 0.12065 0.2794)
			(end 0.12065 0.3048)
			(stroke
				(width 0.1)
				(type default)
			)
			(layer "B.Fab")
		)
		(fp_line
			(start 0.12065 0.3048)
			(end 0.67945 0.3048)
			(stroke
				(width 0.1)
				(type default)
			)
			(layer "B.Fab")
		)
		(fp_line
			(start 0.67945 -0.305054)
			(end 0.12065 -0.305054)
			(stroke
				(width 0.1)
				(type default)
			)
			(layer "B.Fab")
		)
		(fp_line
			(start 0.67945 0.3048)
			(end 0.67945 -0.305054)
			(stroke
				(width 0.1)
				(type default)
			)
			(layer "B.Fab")
		)
		(pad "1" smd circle
			(at 0.40005 0 180)
			(size 0 0)
			(layers "B.Cu" "B.Mask" "B.Paste")
			(net "P3V3")
		)
		(pad "2" smd circle
			(at -0.40005 0 180)
			(size 0 0)
			(layers "B.Cu" "B.Mask" "B.Paste")
			(net "PWRGD_CHC_CPU1_DIMM")
		)
	)
	(footprint ""
		(layer "B.Cu")
		(at 412.191454 -191.20231 180)
		(property "Reference" "R297"
			(at 0 0 0)
			(layer "B.SilkS")
			(hide yes)
			(effects
				(font
					(size 1.27 1.27)
				)
				(justify mirror)
			)
		)
		(property "Value" ""
			(at 0 0 0)
			(layer "B.Fab")
			(effects
				(font
					(size 1.27 1.27)
				)
				(justify mirror)
			)
		)
		(duplicate_pad_numbers_are_jumpers no)
		(fp_line
			(start 0.7874 0.4064)
			(end 0.7874 -0.4064)
			(stroke
				(width 0.1524)
				(type default)
			)
			(layer "B.SilkS")
		)
		(fp_line
			(start 0.7874 -0.4064)
			(end -0.7874 -0.4064)
			(stroke
				(width 0.1524)
				(type default)
			)
			(layer "B.SilkS")
		)
		(fp_line
			(start -0.7874 0.4064)
			(end 0.7874 0.4064)
			(stroke
				(width 0.1524)
				(type default)
			)
			(layer "B.SilkS")
		)
		(fp_line
			(start -0.7874 -0.4064)
			(end -0.7874 0.4064)
			(stroke
				(width 0.1524)
				(type default)
			)
			(layer "B.SilkS")
		)
		(fp_line
			(start 0.67945 0.3048)
			(end 0.67945 -0.305054)
			(stroke
				(width 0.1)
				(type default)
			)
			(layer "B.Fab")
		)
		(fp_line
			(start 0.67945 -0.305054)
			(end 0.12065 -0.305054)
			(stroke
				(width 0.1)
				(type default)
			)
			(layer "B.Fab")
		)
		(fp_line
			(start 0.12065 0.3048)
			(end 0.67945 0.3048)
			(stroke
				(width 0.1)
				(type default)
			)
			(layer "B.Fab")
		)
		(fp_line
			(start 0.12065 0.2794)
			(end 0.12065 0.3048)
			(stroke
				(width 0.1)
				(type default)
			)
			(layer "B.Fab")
		)
		(fp_line
			(start 0.12065 -0.2794)
			(end -0.12065 -0.2794)
			(stroke
				(width 0.1)
				(type default)
			)
			(layer "B.Fab")
		)
		(fp_line
			(start 0.12065 -0.305054)
			(end 0.12065 -0.2794)
			(stroke
				(width 0.1)
				(type default)
			)
			(layer "B.Fab")
		)
		(fp_line
			(start -0.120396 0.3048)
			(end -0.120396 0.2794)
			(stroke
				(width 0.1)
				(type default)
			)
			(layer "B.Fab")
		)
		(fp_line
			(start -0.120396 0.2794)
			(end 0.12065 0.2794)
			(stroke
				(width 0.1)
				(type default)
			)
			(layer "B.Fab")
		)
		(fp_line
			(start -0.12065 -0.2794)
			(end -0.12065 -0.3048)
			(stroke
				(width 0.1)
				(type default)
			)
			(layer "B.Fab")
		)
		(fp_line
			(start -0.12065 -0.3048)
			(end -0.67945 -0.3048)
			(stroke
				(width 0.1)
				(type default)
			)
			(layer "B.Fab")
		)
		(fp_line
			(start -0.67945 0.3048)
			(end -0.120396 0.3048)
			(stroke
				(width 0.1)
				(type default)
			)
			(layer "B.Fab")
		)
		(fp_line
			(start -0.67945 -0.3048)
			(end -0.67945 0.3048)
			(stroke
				(width 0.1)
				(type default)
			)
			(layer "B.Fab")
		)
		(pad "1" smd circle
			(at 0.40005 0)
			(size 0 0)
			(layers "B.Cu" "B.Mask" "B.Paste")
			(net "PWRGD_CHG_CPU0_DIMM0")
		)
		(pad "2" smd circle
			(at -0.40005 0)
			(size 0 0)
			(layers "B.Cu" "B.Mask" "B.Paste")
			(net "PWRGD_CHGL_CPU0")
		)
	)
	(footprint ""
		(layer "B.Cu")
		(at 125.389386 -258.830318)
		(property "Reference" "C2425"
			(at 0 0 0)
			(layer "B.SilkS")
			(hide yes)
			(effects
				(font
					(size 1.27 1.27)
				)
				(justify mirror)
			)
		)
		(property "Value" ""
			(at 0 0 0)
			(layer "B.Fab")
			(effects
				(font
					(size 1.27 1.27)
				)
				(justify mirror)
			)
		)
		(duplicate_pad_numbers_are_jumpers no)
		(fp_line
			(start -0.7874 -0.4064)
			(end -0.7874 0.4064)
			(stroke
				(width 0.1524)
				(type default)
			)
			(layer "B.SilkS")
		)
		(fp_line
			(start -0.7874 0.4064)
			(end 0.7874 0.4064)
			(stroke
				(width 0.1524)
				(type default)
			)
			(layer "B.SilkS")
		)
		(fp_line
			(start 0.7874 -0.4064)
			(end -0.7874 -0.4064)
			(stroke
				(width 0.1524)
				(type default)
			)
			(layer "B.SilkS")
		)
		(fp_line
			(start 0.7874 0.4064)
			(end 0.7874 -0.4064)
			(stroke
				(width 0.1524)
				(type default)
			)
			(layer "B.SilkS")
		)
		(fp_line
			(start -0.67945 -0.3048)
			(end -0.67945 0.3048)
			(stroke
				(width 0.1)
				(type default)
			)
			(layer "B.Fab")
		)
		(fp_line
			(start -0.67945 0.3048)
			(end -0.120396 0.3048)
			(stroke
				(width 0.1)
				(type default)
			)
			(layer "B.Fab")
		)
		(fp_line
			(start -0.12065 -0.3048)
			(end -0.67945 -0.3048)
			(stroke
				(width 0.1)
				(type default)
			)
			(layer "B.Fab")
		)
		(fp_line
			(start -0.12065 -0.2794)
			(end -0.12065 -0.3048)
			(stroke
				(width 0.1)
				(type default)
			)
			(layer "B.Fab")
		)
		(fp_line
			(start -0.120396 0.2794)
			(end 0.12065 0.2794)
			(stroke
				(width 0.1)
				(type default)
			)
			(layer "B.Fab")
		)
		(fp_line
			(start -0.120396 0.3048)
			(end -0.120396 0.2794)
			(stroke
				(width 0.1)
				(type default)
			)
			(layer "B.Fab")
		)
		(fp_line
			(start 0.12065 -0.305054)
			(end 0.12065 -0.2794)
			(stroke
				(width 0.1)
				(type default)
			)
			(layer "B.Fab")
		)
		(fp_line
			(start 0.12065 -0.2794)
			(end -0.12065 -0.2794)
			(stroke
				(width 0.1)
				(type default)
			)
			(layer "B.Fab")
		)
		(fp_line
			(start 0.12065 0.2794)
			(end 0.12065 0.3048)
			(stroke
				(width 0.1)
				(type default)
			)
			(layer "B.Fab")
		)
		(fp_line
			(start 0.12065 0.3048)
			(end 0.67945 0.3048)
			(stroke
				(width 0.1)
				(type default)
			)
			(layer "B.Fab")
		)
		(fp_line
			(start 0.67945 -0.305054)
			(end 0.12065 -0.305054)
			(stroke
				(width 0.1)
				(type default)
			)
			(layer "B.Fab")
		)
		(fp_line
			(start 0.67945 0.3048)
			(end 0.67945 -0.305054)
			(stroke
				(width 0.1)
				(type default)
			)
			(layer "B.Fab")
		)
		(pad "1" smd circle
			(at 0.40005 0 180)
			(size 0 0)
			(layers "B.Cu" "B.Mask" "B.Paste")
			(net "PVDDCR_SOC_P1")
		)
		(pad "2" smd circle
			(at -0.40005 0 180)
			(size 0 0)
			(layers "B.Cu" "B.Mask" "B.Paste")
			(net "GND")
		)
	)
	(footprint ""
		(layer "B.Cu")
		(at 364.439454 -248.47931)
		(property "Reference" "C2174"
			(at 0 0 0)
			(layer "B.SilkS")
			(hide yes)
			(effects
				(font
					(size 1.27 1.27)
				)
				(justify mirror)
			)
		)
		(property "Value" ""
			(at 0 0 0)
			(layer "B.Fab")
			(effects
				(font
					(size 1.27 1.27)
				)
				(justify mirror)
			)
		)
		(duplicate_pad_numbers_are_jumpers no)
		(fp_line
			(start -0.7874 -0.4064)
			(end -0.7874 0.4064)
			(stroke
				(width 0.1524)
				(type default)
			)
			(layer "B.SilkS")
		)
		(fp_line
			(start -0.7874 0.4064)
			(end 0.7874 0.4064)
			(stroke
				(width 0.1524)
				(type default)
			)
			(layer "B.SilkS")
		)
		(fp_line
			(start 0.7874 -0.4064)
			(end -0.7874 -0.4064)
			(stroke
				(width 0.1524)
				(type default)
			)
			(layer "B.SilkS")
		)
		(fp_line
			(start 0.7874 0.4064)
			(end 0.7874 -0.4064)
			(stroke
				(width 0.1524)
				(type default)
			)
			(layer "B.SilkS")
		)
		(fp_line
			(start -0.67945 -0.3048)
			(end -0.67945 0.3048)
			(stroke
				(width 0.1)
				(type default)
			)
			(layer "B.Fab")
		)
		(fp_line
			(start -0.67945 0.3048)
			(end -0.120396 0.3048)
			(stroke
				(width 0.1)
				(type default)
			)
			(layer "B.Fab")
		)
		(fp_line
			(start -0.12065 -0.3048)
			(end -0.67945 -0.3048)
			(stroke
				(width 0.1)
				(type default)
			)
			(layer "B.Fab")
		)
		(fp_line
			(start -0.12065 -0.2794)
			(end -0.12065 -0.3048)
			(stroke
				(width 0.1)
				(type default)
			)
			(layer "B.Fab")
		)
		(fp_line
			(start -0.120396 0.2794)
			(end 0.12065 0.2794)
			(stroke
				(width 0.1)
				(type default)
			)
			(layer "B.Fab")
		)
		(fp_line
			(start -0.120396 0.3048)
			(end -0.120396 0.2794)
			(stroke
				(width 0.1)
				(type default)
			)
			(layer "B.Fab")
		)
		(fp_line
			(start 0.12065 -0.305054)
			(end 0.12065 -0.2794)
			(stroke
				(width 0.1)
				(type default)
			)
			(layer "B.Fab")
		)
		(fp_line
			(start 0.12065 -0.2794)
			(end -0.12065 -0.2794)
			(stroke
				(width 0.1)
				(type default)
			)
			(layer "B.Fab")
		)
		(fp_line
			(start 0.12065 0.2794)
			(end 0.12065 0.3048)
			(stroke
				(width 0.1)
				(type default)
			)
			(layer "B.Fab")
		)
		(fp_line
			(start 0.12065 0.3048)
			(end 0.67945 0.3048)
			(stroke
				(width 0.1)
				(type default)
			)
			(layer "B.Fab")
		)
		(fp_line
			(start 0.67945 -0.305054)
			(end 0.12065 -0.305054)
			(stroke
				(width 0.1)
				(type default)
			)
			(layer "B.Fab")
		)
		(fp_line
			(start 0.67945 0.3048)
			(end 0.67945 -0.305054)
			(stroke
				(width 0.1)
				(type default)
			)
			(layer "B.Fab")
		)
		(pad "1" smd circle
			(at 0.40005 0 180)
			(size 0 0)
			(layers "B.Cu" "B.Mask" "B.Paste")
			(net "PVDDCR_CPU0_P0")
		)
		(pad "2" smd circle
			(at -0.40005 0 180)
			(size 0 0)
			(layers "B.Cu" "B.Mask" "B.Paste")
			(net "GND")
		)
	)
	(footprint ""
		(layer "B.Cu")
		(at 255.905 -338.51596 180)
		(property "Reference" "R829"
			(at 0 0 0)
			(layer "B.SilkS")
			(hide yes)
			(effects
				(font
					(size 1.27 1.27)
				)
				(justify mirror)
			)
		)
		(property "Value" ""
			(at 0 0 0)
			(layer "B.Fab")
			(effects
				(font
					(size 1.27 1.27)
				)
				(justify mirror)
			)
		)
		(duplicate_pad_numbers_are_jumpers no)
		(fp_line
			(start 0.32512 0.175006)
			(end 0.32512 -0.175006)
			(stroke
				(width 0.1)
				(type default)
			)
			(layer "B.Fab")
		)
		(fp_line
			(start 0.32512 -0.175006)
			(end -0.32512 -0.175006)
			(stroke
				(width 0.1)
				(type default)
			)
			(layer "B.Fab")
		)
		(fp_line
			(start -0.32512 0.175006)
			(end 0.32512 0.175006)
			(stroke
				(width 0.1)
				(type default)
			)
			(layer "B.Fab")
		)
		(fp_line
			(start -0.32512 -0.175006)
			(end -0.32512 0.175006)
			(stroke
				(width 0.1)
				(type default)
			)
			(layer "B.Fab")
		)
		(pad "1" smd rect
			(at 0.2667 0)
			(size 0.3048 0.381)
			(layers "B.Cu" "B.Mask" "B.Paste")
			(net "SMB_RT_CPU0_P1_ROM_MUX_2D_R_SCL")
		)
		(pad "2" smd rect
			(at -0.2667 0 180)
			(size 0.3048 0.381)
			(layers "B.Cu" "B.Mask" "B.Paste")
			(net "SMB_RT_CPU0_P1_ROM_MUX_2D_SCL")
		)
	)
	(footprint ""
		(layer "B.Cu")
		(at 175.507142 -421.216074 180)
		(property "Reference" "R6239"
			(at 0 0 0)
			(layer "B.SilkS")
			(hide yes)
			(effects
				(font
					(size 1.27 1.27)
				)
				(justify mirror)
			)
		)
		(property "Value" ""
			(at 0 0 0)
			(layer "B.Fab")
			(effects
				(font
					(size 1.27 1.27)
				)
				(justify mirror)
			)
		)
		(duplicate_pad_numbers_are_jumpers no)
		(fp_line
			(start 0.7874 0.4064)
			(end 0.7874 -0.4064)
			(stroke
				(width 0.1524)
				(type default)
			)
			(layer "B.SilkS")
		)
		(fp_line
			(start 0.7874 -0.4064)
			(end -0.7874 -0.4064)
			(stroke
				(width 0.1524)
				(type default)
			)
			(layer "B.SilkS")
		)
		(fp_line
			(start -0.7874 0.4064)
			(end 0.7874 0.4064)
			(stroke
				(width 0.1524)
				(type default)
			)
			(layer "B.SilkS")
		)
		(fp_line
			(start -0.7874 -0.4064)
			(end -0.7874 0.4064)
			(stroke
				(width 0.1524)
				(type default)
			)
			(layer "B.SilkS")
		)
		(fp_line
			(start 0.67945 0.3048)
			(end 0.67945 -0.305054)
			(stroke
				(width 0.1)
				(type default)
			)
			(layer "B.Fab")
		)
		(fp_line
			(start 0.67945 -0.305054)
			(end 0.12065 -0.305054)
			(stroke
				(width 0.1)
				(type default)
			)
			(layer "B.Fab")
		)
		(fp_line
			(start 0.12065 0.3048)
			(end 0.67945 0.3048)
			(stroke
				(width 0.1)
				(type default)
			)
			(layer "B.Fab")
		)
		(fp_line
			(start 0.12065 0.2794)
			(end 0.12065 0.3048)
			(stroke
				(width 0.1)
				(type default)
			)
			(layer "B.Fab")
		)
		(fp_line
			(start 0.12065 -0.2794)
			(end -0.12065 -0.2794)
			(stroke
				(width 0.1)
				(type default)
			)
			(layer "B.Fab")
		)
		(fp_line
			(start 0.12065 -0.305054)
			(end 0.12065 -0.2794)
			(stroke
				(width 0.1)
				(type default)
			)
			(layer "B.Fab")
		)
		(fp_line
			(start -0.120396 0.3048)
			(end -0.120396 0.2794)
			(stroke
				(width 0.1)
				(type default)
			)
			(layer "B.Fab")
		)
		(fp_line
			(start -0.120396 0.2794)
			(end 0.12065 0.2794)
			(stroke
				(width 0.1)
				(type default)
			)
			(layer "B.Fab")
		)
		(fp_line
			(start -0.12065 -0.2794)
			(end -0.12065 -0.3048)
			(stroke
				(width 0.1)
				(type default)
			)
			(layer "B.Fab")
		)
		(fp_line
			(start -0.12065 -0.3048)
			(end -0.67945 -0.3048)
			(stroke
				(width 0.1)
				(type default)
			)
			(layer "B.Fab")
		)
		(fp_line
			(start -0.67945 0.3048)
			(end -0.120396 0.3048)
			(stroke
				(width 0.1)
				(type default)
			)
			(layer "B.Fab")
		)
		(fp_line
			(start -0.67945 -0.3048)
			(end -0.67945 0.3048)
			(stroke
				(width 0.1)
				(type default)
			)
			(layer "B.Fab")
		)
		(pad "1" smd circle
			(at 0.40005 0)
			(size 0 0)
			(layers "B.Cu" "B.Mask" "B.Paste")
			(net "P3V3_AUX")
		)
		(pad "2" smd circle
			(at -0.40005 0)
			(size 0 0)
			(layers "B.Cu" "B.Mask" "B.Paste")
			(net "HSC_D_OC")
		)
	)
	(footprint ""
		(layer "B.Cu")
		(at 129.289048 -156.393134 -90)
		(property "Reference" "PC351_3"
			(at 0 0 90)
			(layer "B.SilkS")
			(hide yes)
			(effects
				(font
					(size 1.27 1.27)
				)
				(justify mirror)
			)
		)
		(property "Value" ""
			(at 0 0 90)
			(layer "B.Fab")
			(effects
				(font
					(size 1.27 1.27)
				)
				(justify mirror)
			)
		)
		(duplicate_pad_numbers_are_jumpers no)
		(fp_line
			(start -1.524 0.762)
			(end 1.524 0.762)
			(stroke
				(width 0.1524)
				(type default)
			)
			(layer "B.SilkS")
		)
		(fp_line
			(start 1.524 0.762)
			(end 1.524 -0.762)
			(stroke
				(width 0.1524)
				(type default)
			)
			(layer "B.SilkS")
		)
		(fp_line
			(start -1.524 -0.762)
			(end -1.524 0.762)
			(stroke
				(width 0.1524)
				(type default)
			)
			(layer "B.SilkS")
		)
		(fp_line
			(start 1.524 -0.762)
			(end -1.524 -0.762)
			(stroke
				(width 0.1524)
				(type default)
			)
			(layer "B.SilkS")
		)
		(fp_line
			(start -1.1049 0.724916)
			(end -1.1049 -0.724916)
			(stroke
				(width 0.1)
				(type default)
			)
			(layer "B.Fab")
		)
		(fp_line
			(start 1.1049 0.724916)
			(end -1.1049 0.724916)
			(stroke
				(width 0.1)
				(type default)
			)
			(layer "B.Fab")
		)
		(fp_line
			(start -1.1049 -0.724916)
			(end 1.1049 -0.724916)
			(stroke
				(width 0.1)
				(type default)
			)
			(layer "B.Fab")
		)
		(fp_line
			(start 1.1049 -0.724916)
			(end 1.1049 0.724916)
			(stroke
				(width 0.1)
				(type default)
			)
			(layer "B.Fab")
		)
		(pad "1" smd rect
			(at 0.889 0 270)
			(size 1.016 1.27)
			(layers "B.Cu" "B.Mask" "B.Paste")
			(net "SW_P12V_AUX_PVDDCR_SOC_P1_FLT")
		)
		(pad "2" smd rect
			(at -0.889 0 270)
			(size 1.016 1.27)
			(layers "B.Cu" "B.Mask" "B.Paste")
			(net "GND")
		)
	)
)
